# S9S_MB_2U (Grand Teton) — schematic netlist excerpt (pin names and nets, part order shuffled) for the footprints in the layout excerpt that follows; sources: Cadence DE-HDL packaged netlist, KiCad conversion of 03242023_DA0F0TMBIJ0_F0T_Motherboard_J_brd_V01_OCP.brd

PR3995  Q_RES  0 5% CHIP  pkg 0402LF  page 303 : A = HSC_FLT_TYPE_4 ; B = HSC_FLT_TYPE
R1671  Q_RES  0 5% CHIP  pkg 0402LF  page 153 : A = OCP_SFF_AUX_PWR_EN ; B = OCP_SFF_AUX_PWR_EN_R

(kicad_pcb
	(version 20260206)
	(generator "pcbnew")
	(generator_version "10.0")
	(general
		(thickness 1.6)
		(legacy_teardrops no)
	)
	(paper "A4")
	(title_block
		(title "03242023_DA0F0TMBIJ0_F0T_Motherboard_J_brd_V01_OCP.brd")
		(comment 1 "Grand Teton / footprints 3402-3403 of 6105")
	)
	(layers
		(0 "F.Cu" signal "TOP")
		(4 "In1.Cu" signal "GND")
		(6 "In2.Cu" signal "IN1")
		(8 "In3.Cu" signal "GND1")
		(10 "In4.Cu" signal "IN2")
		(12 "In5.Cu" signal "GND2")
		(14 "In6.Cu" signal "IN3")
		(16 "In7.Cu" signal "GND3")
		(18 "In8.Cu" signal "VCC")
		(20 "In9.Cu" signal "VCC1")
		(22 "In10.Cu" signal "GND4")
		(24 "In11.Cu" signal "IN4")
		(26 "In12.Cu" signal "GND5")
		(28 "In13.Cu" signal "IN5")
		(30 "In14.Cu" signal "GND6")
		(32 "In15.Cu" signal "IN6")
		(34 "In16.Cu" signal "GND7")
		(2 "B.Cu" signal "BOTTOM")
		(9 "F.Adhes" user "F.Adhesive")
		(11 "B.Adhes" user "B.Adhesive")
		(13 "F.Paste" user "Package Geometry/Pastemask Top")
		(15 "B.Paste" user "Package Geometry/Pastemask Bottom")
		(5 "F.SilkS" user "Ref Des/Silkscreen Top")
		(7 "B.SilkS" user "Ref Des/Silkscreen Bottom")
		(1 "F.Mask" user "Board Geometry/Soldermask Top")
		(3 "B.Mask" user "Board Geometry/Soldermask Bottom")
		(17 "Dwgs.User" user "User.Drawings")
		(19 "Cmts.User" user "User.Comments")
		(21 "Eco1.User" user "User.Eco1")
		(23 "Eco2.User" user "User.Eco2")
		(25 "Edge.Cuts" user "Board Geometry/Outline")
		(27 "Margin" user)
		(31 "F.CrtYd" user "Package Geometry/Place Bound Top")
		(29 "B.CrtYd" user "Package Geometry/Place Bound Bottom")
		(35 "F.Fab" user "Ref Des/Assembly Top")
		(33 "B.Fab" user "Ref Des/Assembly Bottom")
	)
	(footprint ""
		(layer "F.Cu")
		(at 237.401608 -403.705822)
		(property "Reference" "PR3995"
			(at 0 0 0)
			(layer "F.SilkS")
			(hide yes)
			(effects
				(font
					(size 1.27 1.27)
				)
			)
		)
		(property "Value" ""
			(at 0 0 0)
			(layer "F.Fab")
			(effects
				(font
					(size 1.27 1.27)
				)
			)
		)
		(duplicate_pad_numbers_are_jumpers no)
		(fp_line
			(start -0.7874 -0.4064)
			(end 0.7874 -0.4064)
			(stroke
				(width 0.1524)
				(type default)
			)
			(layer "F.SilkS")
		)
		(fp_line
			(start -0.7874 0.4064)
			(end -0.7874 -0.4064)
			(stroke
				(width 0.1524)
				(type default)
			)
			(layer "F.SilkS")
		)
		(fp_line
			(start 0.7874 -0.4064)
			(end 0.7874 0.4064)
			(stroke
				(width 0.1524)
				(type default)
			)
			(layer "F.SilkS")
		)
		(fp_line
			(start 0.7874 0.4064)
			(end -0.7874 0.4064)
			(stroke
				(width 0.1524)
				(type default)
			)
			(layer "F.SilkS")
		)
		(fp_line
			(start -0.67945 -0.305054)
			(end -0.12065 -0.305054)
			(stroke
				(width 0.1)
				(type default)
			)
			(layer "F.Fab")
		)
		(fp_line
			(start -0.67945 0.3048)
			(end -0.67945 -0.305054)
			(stroke
				(width 0.1)
				(type default)
			)
			(layer "F.Fab")
		)
		(fp_line
			(start -0.12065 -0.305054)
			(end -0.12065 -0.2794)
			(stroke
				(width 0.1)
				(type default)
			)
			(layer "F.Fab")
		)
		(fp_line
			(start -0.12065 -0.2794)
			(end 0.12065 -0.2794)
			(stroke
				(width 0.1)
				(type default)
			)
			(layer "F.Fab")
		)
		(fp_line
			(start -0.12065 0.2794)
			(end -0.12065 0.3048)
			(stroke
				(width 0.1)
				(type default)
			)
			(layer "F.Fab")
		)
		(fp_line
			(start -0.12065 0.3048)
			(end -0.67945 0.3048)
			(stroke
				(width 0.1)
				(type default)
			)
			(layer "F.Fab")
		)
		(fp_line
			(start 0.120396 0.2794)
			(end -0.12065 0.2794)
			(stroke
				(width 0.1)
				(type default)
			)
			(layer "F.Fab")
		)
		(fp_line
			(start 0.120396 0.3048)
			(end 0.120396 0.2794)
			(stroke
				(width 0.1)
				(type default)
			)
			(layer "F.Fab")
		)
		(fp_line
			(start 0.12065 -0.3048)
			(end 0.67945 -0.3048)
			(stroke
				(width 0.1)
				(type default)
			)
			(layer "F.Fab")
		)
		(fp_line
			(start 0.12065 -0.2794)
			(end 0.12065 -0.3048)
			(stroke
				(width 0.1)
				(type default)
			)
			(layer "F.Fab")
		)
		(fp_line
			(start 0.67945 -0.3048)
			(end 0.67945 0.3048)
			(stroke
				(width 0.1)
				(type default)
			)
			(layer "F.Fab")
		)
		(fp_line
			(start 0.67945 0.3048)
			(end 0.120396 0.3048)
			(stroke
				(width 0.1)
				(type default)
			)
			(layer "F.Fab")
		)
		(pad "1" smd circle
			(at -0.40005 0)
			(size 0 0)
			(layers "F.Cu" "F.Mask" "F.Paste")
			(net "HSC_FLT_TYPE_4")
		)
		(pad "2" smd circle
			(at 0.40005 0)
			(size 0 0)
			(layers "F.Cu" "F.Mask" "F.Paste")
			(net "HSC_FLT_TYPE")
		)
	)
	(footprint ""
		(layer "F.Cu")
		(at 434.805328 -16.188182 -90)
		(property "Reference" "R1671"
			(at 0 0 270)
			(layer "F.SilkS")
			(hide yes)
			(effects
				(font
					(size 1.27 1.27)
				)
			)
		)
		(property "Value" ""
			(at 0 0 270)
			(layer "F.Fab")
			(effects
				(font
					(size 1.27 1.27)
				)
			)
		)
		(duplicate_pad_numbers_are_jumpers no)
		(fp_line
			(start -0.7874 0.4064)
			(end -0.7874 -0.4064)
			(stroke
				(width 0.1524)
				(type default)
			)
			(layer "F.SilkS")
		)
		(fp_line
			(start 0.7874 0.4064)
			(end -0.7874 0.4064)
			(stroke
				(width 0.1524)
				(type default)
			)
			(layer "F.SilkS")
		)
		(fp_line
			(start -0.7874 -0.4064)
			(end 0.7874 -0.4064)
			(stroke
				(width 0.1524)
				(type default)
			)
			(layer "F.SilkS")
		)
		(fp_line
			(start 0.7874 -0.4064)
			(end 0.7874 0.4064)
			(stroke
				(width 0.1524)
				(type default)
			)
			(layer "F.SilkS")
		)
		(fp_line
			(start -0.67945 0.3048)
			(end -0.67945 -0.305054)
			(stroke
				(width 0.1)
				(type default)
			)
			(layer "F.Fab")
		)
		(fp_line
			(start -0.12065 0.3048)
			(end -0.67945 0.3048)
			(stroke
				(width 0.1)
				(type default)
			)
			(layer "F.Fab")
		)
		(fp_line
			(start 0.120396 0.3048)
			(end 0.120396 0.2794)
			(stroke
				(width 0.1)
				(type default)
			)
			(layer "F.Fab")
		)
		(fp_line
			(start 0.67945 0.3048)
			(end 0.120396 0.3048)
			(stroke
				(width 0.1)
				(type default)
			)
			(layer "F.Fab")
		)
		(fp_line
			(start -0.12065 0.2794)
			(end -0.12065 0.3048)
			(stroke
				(width 0.1)
				(type default)
			)
			(layer "F.Fab")
		)
		(fp_line
			(start 0.120396 0.2794)
			(end -0.12065 0.2794)
			(stroke
				(width 0.1)
				(type default)
			)
			(layer "F.Fab")
		)
		(fp_line
			(start -0.12065 -0.2794)
			(end 0.12065 -0.2794)
			(stroke
				(width 0.1)
				(type default)
			)
			(layer "F.Fab")
		)
		(fp_line
			(start 0.12065 -0.2794)
			(end 0.12065 -0.3048)
			(stroke
				(width 0.1)
				(type default)
			)
			(layer "F.Fab")
		)
		(fp_line
			(start 0.12065 -0.3048)
			(end 0.67945 -0.3048)
			(stroke
				(width 0.1)
				(type default)
			)
			(layer "F.Fab")
		)
		(fp_line
			(start 0.67945 -0.3048)
			(end 0.67945 0.3048)
			(stroke
				(width 0.1)
				(type default)
			)
			(layer "F.Fab")
		)
		(fp_line
			(start -0.67945 -0.305054)
			(end -0.12065 -0.305054)
			(stroke
				(width 0.1)
				(type default)
			)
			(layer "F.Fab")
		)
		(fp_line
			(start -0.12065 -0.305054)
			(end -0.12065 -0.2794)
			(stroke
				(width 0.1)
				(type default)
			)
			(layer "F.Fab")
		)
		(pad "1" smd circle
			(at -0.40005 0 270)
			(size 0 0)
			(layers "F.Cu" "F.Mask" "F.Paste")
			(net "OCP_SFF_AUX_PWR_EN")
		)
		(pad "2" smd circle
			(at 0.40005 0 270)
			(size 0 0)
			(layers "F.Cu" "F.Mask" "F.Paste")
			(net "OCP_SFF_AUX_PWR_EN_R")
		)
	)
)
